# T6G (Grand Teton) — schematic netlist excerpt (pin names and nets, part order shuffled) for the footprints in the layout excerpt that follows; sources: Cadence DE-HDL packaged netlist, KiCad conversion of 04192023_DAF0TMB3IC0_F0TG_MB_C_brd_V02_OCP.brd

PR261  Q_RES  0 5% CHIP  pkg 0402LF  page 218 : A = PVDDCR_CPU1_P1_VOS1 ; B = PVDDCR_CPU1_P1
C786  Q_CAP  1UF 4V 20% X6S  pkg 0201  page 301 : A = P0V9_CPU0_RT2_2A ; B = GND
C2177  Q_CAP  22UF 4V 20% X6S  pkg C0402  page 69 : A = PVDDCR_CPU0_P0 ; B = GND

(kicad_pcb
	(version 20260206)
	(generator "pcbnew")
	(generator_version "10.0")
	(general
		(thickness 1.6)
		(legacy_teardrops no)
	)
	(paper "A4")
	(title_block
		(title "04192023_DAF0TMB3IC0_F0TG_MB_C_brd_V02_OCP.brd")
		(comment 1 "Grand Teton / footprints 7551-7553 of 8354")
	)
	(layers
		(0 "F.Cu" signal "TOP")
		(4 "In1.Cu" signal "GND")
		(6 "In2.Cu" signal "IN1")
		(8 "In3.Cu" signal "GND1")
		(10 "In4.Cu" signal "IN2")
		(12 "In5.Cu" signal "GND2")
		(14 "In6.Cu" signal "IN3")
		(16 "In7.Cu" signal "GND3")
		(18 "In8.Cu" signal "VCC")
		(20 "In9.Cu" signal "VCC1")
		(22 "In10.Cu" signal "GND4")
		(24 "In11.Cu" signal "IN4")
		(26 "In12.Cu" signal "GND5")
		(28 "In13.Cu" signal "IN5")
		(30 "In14.Cu" signal "GND6")
		(32 "In15.Cu" signal "IN6")
		(34 "In16.Cu" signal "GND7")
		(2 "B.Cu" signal "BOTTOM")
		(9 "F.Adhes" user "F.Adhesive")
		(11 "B.Adhes" user "B.Adhesive")
		(13 "F.Paste" user "Package Geometry/Pastemask Top")
		(15 "B.Paste" user "Package Geometry/Pastemask Bottom")
		(5 "F.SilkS" user "Ref Des/Silkscreen Top")
		(7 "B.SilkS" user "Ref Des/Silkscreen Bottom")
		(1 "F.Mask" user "Board Geometry/Soldermask Top")
		(3 "B.Mask" user "Board Geometry/Soldermask Bottom")
		(17 "Dwgs.User" user "User.Drawings")
		(19 "Cmts.User" user "User.Comments")
		(21 "Eco1.User" user "User.Eco1")
		(23 "Eco2.User" user "User.Eco2")
		(25 "Edge.Cuts" user "Board Geometry/Outline")
		(27 "Margin" user)
		(31 "F.CrtYd" user "Package Geometry/Place Bound Top")
		(29 "B.CrtYd" user "Package Geometry/Place Bound Bottom")
		(35 "F.Fab" user "Ref Des/Assembly Top")
		(33 "B.Fab" user "Ref Des/Assembly Bottom")
	)
	(footprint ""
		(layer "B.Cu")
		(at 369.570254 -249.36831)
		(property "Reference" "C2177"
			(at 0 0 0)
			(layer "B.SilkS")
			(hide yes)
			(effects
				(font
					(size 1.27 1.27)
				)
				(justify mirror)
			)
		)
		(property "Value" ""
			(at 0 0 0)
			(layer "B.Fab")
			(effects
				(font
					(size 1.27 1.27)
				)
				(justify mirror)
			)
		)
		(duplicate_pad_numbers_are_jumpers no)
		(fp_line
			(start -0.7874 -0.4064)
			(end -0.7874 0.4064)
			(stroke
				(width 0.1524)
				(type default)
			)
			(layer "B.SilkS")
		)
		(fp_line
			(start -0.7874 0.4064)
			(end 0.7874 0.4064)
			(stroke
				(width 0.1524)
				(type default)
			)
			(layer "B.SilkS")
		)
		(fp_line
			(start 0.7874 -0.4064)
			(end -0.7874 -0.4064)
			(stroke
				(width 0.1524)
				(type default)
			)
			(layer "B.SilkS")
		)
		(fp_line
			(start 0.7874 0.4064)
			(end 0.7874 -0.4064)
			(stroke
				(width 0.1524)
				(type default)
			)
			(layer "B.SilkS")
		)
		(fp_line
			(start -0.67945 -0.3048)
			(end -0.67945 0.3048)
			(stroke
				(width 0.1)
				(type default)
			)
			(layer "B.Fab")
		)
		(fp_line
			(start -0.67945 0.3048)
			(end -0.120396 0.3048)
			(stroke
				(width 0.1)
				(type default)
			)
			(layer "B.Fab")
		)
		(fp_line
			(start -0.12065 -0.3048)
			(end -0.67945 -0.3048)
			(stroke
				(width 0.1)
				(type default)
			)
			(layer "B.Fab")
		)
		(fp_line
			(start -0.12065 -0.2794)
			(end -0.12065 -0.3048)
			(stroke
				(width 0.1)
				(type default)
			)
			(layer "B.Fab")
		)
		(fp_line
			(start -0.120396 0.2794)
			(end 0.12065 0.2794)
			(stroke
				(width 0.1)
				(type default)
			)
			(layer "B.Fab")
		)
		(fp_line
			(start -0.120396 0.3048)
			(end -0.120396 0.2794)
			(stroke
				(width 0.1)
				(type default)
			)
			(layer "B.Fab")
		)
		(fp_line
			(start 0.12065 -0.305054)
			(end 0.12065 -0.2794)
			(stroke
				(width 0.1)
				(type default)
			)
			(layer "B.Fab")
		)
		(fp_line
			(start 0.12065 -0.2794)
			(end -0.12065 -0.2794)
			(stroke
				(width 0.1)
				(type default)
			)
			(layer "B.Fab")
		)
		(fp_line
			(start 0.12065 0.2794)
			(end 0.12065 0.3048)
			(stroke
				(width 0.1)
				(type default)
			)
			(layer "B.Fab")
		)
		(fp_line
			(start 0.12065 0.3048)
			(end 0.67945 0.3048)
			(stroke
				(width 0.1)
				(type default)
			)
			(layer "B.Fab")
		)
		(fp_line
			(start 0.67945 -0.305054)
			(end 0.12065 -0.305054)
			(stroke
				(width 0.1)
				(type default)
			)
			(layer "B.Fab")
		)
		(fp_line
			(start 0.67945 0.3048)
			(end 0.67945 -0.305054)
			(stroke
				(width 0.1)
				(type default)
			)
			(layer "B.Fab")
		)
		(pad "1" smd circle
			(at 0.40005 0 180)
			(size 0 0)
			(layers "B.Cu" "B.Mask" "B.Paste")
			(net "PVDDCR_CPU0_P0")
		)
		(pad "2" smd circle
			(at -0.40005 0 180)
			(size 0 0)
			(layers "B.Cu" "B.Mask" "B.Paste")
			(net "GND")
		)
	)
	(footprint ""
		(layer "B.Cu")
		(at 421.00627 -395.148562 90)
		(property "Reference" "C786"
			(at 0 0 90)
			(layer "B.SilkS")
			(hide yes)
			(effects
				(font
					(size 1.27 1.27)
				)
				(justify mirror)
			)
		)
		(property "Value" ""
			(at 0 0 90)
			(layer "B.Fab")
			(effects
				(font
					(size 1.27 1.27)
				)
				(justify mirror)
			)
		)
		(duplicate_pad_numbers_are_jumpers no)
		(fp_line
			(start 0.299974 -0.150114)
			(end -0.299974 -0.150114)
			(stroke
				(width 0.1)
				(type default)
			)
			(layer "B.Fab")
		)
		(fp_line
			(start -0.299974 -0.150114)
			(end -0.299974 0.150114)
			(stroke
				(width 0.1)
				(type default)
			)
			(layer "B.Fab")
		)
		(fp_line
			(start 0.299974 0.150114)
			(end 0.299974 -0.150114)
			(stroke
				(width 0.1)
				(type default)
			)
			(layer "B.Fab")
		)
		(fp_line
			(start -0.299974 0.150114)
			(end 0.299974 0.150114)
			(stroke
				(width 0.1)
				(type default)
			)
			(layer "B.Fab")
		)
		(pad "1" smd rect
			(at 0.2667 0 270)
			(size 0.3048 0.381)
			(layers "B.Cu" "B.Mask" "B.Paste")
			(net "P0V9_CPU0_RT2_2A")
		)
		(pad "2" smd rect
			(at -0.2667 0 270)
			(size 0.3048 0.381)
			(layers "B.Cu" "B.Mask" "B.Paste")
			(net "GND")
		)
	)
	(footprint ""
		(layer "B.Cu")
		(at 83.460844 -337.643724 -90)
		(property "Reference" "PR261"
			(at 0 0 90)
			(layer "B.SilkS")
			(hide yes)
			(effects
				(font
					(size 1.27 1.27)
				)
				(justify mirror)
			)
		)
		(property "Value" ""
			(at 0 0 90)
			(layer "B.Fab")
			(effects
				(font
					(size 1.27 1.27)
				)
				(justify mirror)
			)
		)
		(duplicate_pad_numbers_are_jumpers no)
		(fp_line
			(start -0.7874 0.4064)
			(end 0.7874 0.4064)
			(stroke
				(width 0.1524)
				(type default)
			)
			(layer "B.SilkS")
		)
		(fp_line
			(start 0.7874 0.4064)
			(end 0.7874 -0.4064)
			(stroke
				(width 0.1524)
				(type default)
			)
			(layer "B.SilkS")
		)
		(fp_line
			(start -0.7874 -0.4064)
			(end -0.7874 0.4064)
			(stroke
				(width 0.1524)
				(type default)
			)
			(layer "B.SilkS")
		)
		(fp_line
			(start 0.7874 -0.4064)
			(end -0.7874 -0.4064)
			(stroke
				(width 0.1524)
				(type default)
			)
			(layer "B.SilkS")
		)
		(fp_line
			(start -0.67945 0.3048)
			(end -0.120396 0.3048)
			(stroke
				(width 0.1)
				(type default)
			)
			(layer "B.Fab")
		)
		(fp_line
			(start -0.120396 0.3048)
			(end -0.120396 0.2794)
			(stroke
				(width 0.1)
				(type default)
			)
			(layer "B.Fab")
		)
		(fp_line
			(start 0.12065 0.3048)
			(end 0.67945 0.3048)
			(stroke
				(width 0.1)
				(type default)
			)
			(layer "B.Fab")
		)
		(fp_line
			(start 0.67945 0.3048)
			(end 0.67945 -0.305054)
			(stroke
				(width 0.1)
				(type default)
			)
			(layer "B.Fab")
		)
		(fp_line
			(start -0.120396 0.2794)
			(end 0.12065 0.2794)
			(stroke
				(width 0.1)
				(type default)
			)
			(layer "B.Fab")
		)
		(fp_line
			(start 0.12065 0.2794)
			(end 0.12065 0.3048)
			(stroke
				(width 0.1)
				(type default)
			)
			(layer "B.Fab")
		)
		(fp_line
			(start -0.12065 -0.2794)
			(end -0.12065 -0.3048)
			(stroke
				(width 0.1)
				(type default)
			)
			(layer "B.Fab")
		)
		(fp_line
			(start 0.12065 -0.2794)
			(end -0.12065 -0.2794)
			(stroke
				(width 0.1)
				(type default)
			)
			(layer "B.Fab")
		)
		(fp_line
			(start -0.67945 -0.3048)
			(end -0.67945 0.3048)
			(stroke
				(width 0.1)
				(type default)
			)
			(layer "B.Fab")
		)
		(fp_line
			(start -0.12065 -0.3048)
			(end -0.67945 -0.3048)
			(stroke
				(width 0.1)
				(type default)
			)
			(layer "B.Fab")
		)
		(fp_line
			(start 0.12065 -0.305054)
			(end 0.12065 -0.2794)
			(stroke
				(width 0.1)
				(type default)
			)
			(layer "B.Fab")
		)
		(fp_line
			(start 0.67945 -0.305054)
			(end 0.12065 -0.305054)
			(stroke
				(width 0.1)
				(type default)
			)
			(layer "B.Fab")
		)
		(pad "1" smd circle
			(at 0.40005 0 90)
			(size 0 0)
			(layers "B.Cu" "B.Mask" "B.Paste")
			(net "PVDDCR_CPU1_P1_VOS1")
		)
		(pad "2" smd circle
			(at -0.40005 0 90)
			(size 0 0)
			(layers "B.Cu" "B.Mask" "B.Paste")
			(net "PVDDCR_CPU1_P1")
		)
	)
)
